(kicad_pcb
	(version 20260206)
	(generator "pcbnew")
	(generator_version "10.0")
	(general
		(thickness 1.6)
		(legacy_teardrops no)
	)
	(paper "A4")
	(title_block
		(title "01162023_DA0F0TEBIF0_F0T_Expander_BD_F_brd_V02_OCP.brd")
		(comment 1 "Grand Teton / footprints 8915-8924 of 9728")
	)
	(layers
		(0 "F.Cu" signal "TOP")
		(4 "In1.Cu" signal "GND")
		(6 "In2.Cu" signal "VCC")
		(8 "In3.Cu" signal "VCC1")
		(10 "In4.Cu" signal "GND1")
		(12 "In5.Cu" signal "IN1")
		(14 "In6.Cu" signal "GND2")
		(16 "In7.Cu" signal "IN2")
		(18 "In8.Cu" signal "GND3")
		(20 "In9.Cu" signal "IN3")
		(22 "In10.Cu" signal "GND4")
		(24 "In11.Cu" signal "IN4")
		(26 "In12.Cu" signal "GND5")
		(28 "In13.Cu" signal "IN5")
		(30 "In14.Cu" signal "GND6")
		(32 "In15.Cu" signal "IN6")
		(34 "In16.Cu" signal "GND7")
		(2 "B.Cu" signal "BOTTOM")
		(9 "F.Adhes" user "F.Adhesive")
		(11 "B.Adhes" user "B.Adhesive")
		(13 "F.Paste" user "Package Geometry/Pastemask Top")
		(15 "B.Paste" user "Package Geometry/Pastemask Bottom")
		(5 "F.SilkS" user "Ref Des/Silkscreen Top")
		(7 "B.SilkS" user "Ref Des/Silkscreen Bottom")
		(1 "F.Mask" user "Board Geometry/Soldermask Top")
		(3 "B.Mask" user "Board Geometry/Soldermask Bottom")
		(17 "Dwgs.User" user "User.Drawings")
		(19 "Cmts.User" user "User.Comments")
		(21 "Eco1.User" user "User.Eco1")
		(23 "Eco2.User" user "User.Eco2")
		(25 "Edge.Cuts" user "Board Geometry/Outline")
		(27 "Margin" user)
		(31 "F.CrtYd" user "Package Geometry/Place Bound Top")
		(29 "B.CrtYd" user "Package Geometry/Place Bound Bottom")
		(35 "F.Fab" user "Ref Des/Assembly Top")
		(33 "B.Fab" user "Ref Des/Assembly Bottom")
	)
	(footprint ""
		(layer "B.Cu")
		(at 78.501748 -295.422066 180)
		(property "Reference" "C2903"
			(at 0 0 0)
			(layer "B.SilkS")
			(hide yes)
			(effects
				(font
					(size 1.27 1.27)
				)
				(justify mirror)
			)
		)
		(property "Value" ""
			(at 0 0 0)
			(layer "B.Fab")
			(effects
				(font
					(size 1.27 1.27)
				)
				(justify mirror)
			)
		)
		(duplicate_pad_numbers_are_jumpers no)
		(fp_line
			(start 1.2954 0.5842)
			(end 1.2954 -0.5842)
			(stroke
				(width 0.1524)
				(type default)
			)
			(layer "B.SilkS")
		)
		(fp_line
			(start 1.2954 -0.5842)
			(end -1.2954 -0.5842)
			(stroke
				(width 0.1524)
				(type default)
			)
			(layer "B.SilkS")
		)
		(fp_line
			(start -1.2954 0.5842)
			(end 1.2954 0.5842)
			(stroke
				(width 0.1524)
				(type default)
			)
			(layer "B.SilkS")
		)
		(fp_line
			(start -1.2954 -0.5842)
			(end -1.2954 0.5842)
			(stroke
				(width 0.1524)
				(type default)
			)
			(layer "B.SilkS")
		)
		(fp_line
			(start 1.1938 0.4064)
			(end 1.1938 -0.4064)
			(stroke
				(width 0.1)
				(type default)
			)
			(layer "B.Fab")
		)
		(fp_line
			(start 1.1938 -0.4064)
			(end 0.8636 -0.4064)
			(stroke
				(width 0.1)
				(type default)
			)
			(layer "B.Fab")
		)
		(fp_line
			(start 0.8636 0.4572)
			(end 0.8636 0.4064)
			(stroke
				(width 0.1)
				(type default)
			)
			(layer "B.Fab")
		)
		(fp_line
			(start 0.8636 0.4064)
			(end 1.1938 0.4064)
			(stroke
				(width 0.1)
				(type default)
			)
			(layer "B.Fab")
		)
		(fp_line
			(start 0.8636 -0.4064)
			(end 0.8636 -0.4572)
			(stroke
				(width 0.1)
				(type default)
			)
			(layer "B.Fab")
		)
		(fp_line
			(start 0.8636 -0.4572)
			(end -0.8636 -0.4572)
			(stroke
				(width 0.1)
				(type default)
			)
			(layer "B.Fab")
		)
		(fp_line
			(start -0.8636 0.4572)
			(end 0.8636 0.4572)
			(stroke
				(width 0.1)
				(type default)
			)
			(layer "B.Fab")
		)
		(fp_line
			(start -0.8636 0.4064)
			(end -0.8636 0.4572)
			(stroke
				(width 0.1)
				(type default)
			)
			(layer "B.Fab")
		)
		(fp_line
			(start -0.8636 -0.4064)
			(end -1.1938 -0.4064)
			(stroke
				(width 0.1)
				(type default)
			)
			(layer "B.Fab")
		)
		(fp_line
			(start -0.8636 -0.4572)
			(end -0.8636 -0.4064)
			(stroke
				(width 0.1)
				(type default)
			)
			(layer "B.Fab")
		)
		(fp_line
			(start -1.1938 0.4064)
			(end -0.8636 0.4064)
			(stroke
				(width 0.1)
				(type default)
			)
			(layer "B.Fab")
		)
		(fp_line
			(start -1.1938 -0.4064)
			(end -1.1938 0.4064)
			(stroke
				(width 0.1)
				(type default)
			)
			(layer "B.Fab")
		)
		(pad "1" smd rect
			(at 0.7366 0 90)
			(size 0.7112 0.8128)
			(layers "B.Cu" "B.Mask" "B.Paste")
			(net "P1V25_PEX0")
		)
		(pad "2" smd rect
			(at -0.7366 0 90)
			(size 0.7112 0.8128)
			(layers "B.Cu" "B.Mask" "B.Paste")
			(net "GND")
		)
	)
	(footprint ""
		(layer "B.Cu")
		(at 56.26989 -305.399948 -90)
		(property "Reference" "C2970"
			(at 0 0 90)
			(layer "B.SilkS")
			(hide yes)
			(effects
				(font
					(size 1.27 1.27)
				)
				(justify mirror)
			)
		)
		(property "Value" ""
			(at 0 0 90)
			(layer "B.Fab")
			(effects
				(font
					(size 1.27 1.27)
				)
				(justify mirror)
			)
		)
		(duplicate_pad_numbers_are_jumpers no)
		(fp_line
			(start -0.299974 0.150114)
			(end 0.299974 0.150114)
			(stroke
				(width 0.1)
				(type default)
			)
			(layer "B.Fab")
		)
		(fp_line
			(start 0.299974 0.150114)
			(end 0.299974 -0.150114)
			(stroke
				(width 0.1)
				(type default)
			)
			(layer "B.Fab")
		)
		(fp_line
			(start -0.299974 -0.150114)
			(end -0.299974 0.150114)
			(stroke
				(width 0.1)
				(type default)
			)
			(layer "B.Fab")
		)
		(fp_line
			(start 0.299974 -0.150114)
			(end -0.299974 -0.150114)
			(stroke
				(width 0.1)
				(type default)
			)
			(layer "B.Fab")
		)
		(pad "1" smd rect
			(at 0.2667 0 90)
			(size 0.3048 0.381)
			(layers "B.Cu" "B.Mask" "B.Paste")
			(net "P1V25_SERDES_VDDPLL_PEX0")
		)
		(pad "2" smd rect
			(at -0.2667 0 90)
			(size 0.3048 0.381)
			(layers "B.Cu" "B.Mask" "B.Paste")
			(net "GND")
		)
	)
	(footprint ""
		(layer "B.Cu")
		(at 60.599828 -292.099746 90)
		(property "Reference" "C1223"
			(at 0 0 90)
			(layer "B.SilkS")
			(hide yes)
			(effects
				(font
					(size 1.27 1.27)
				)
				(justify mirror)
			)
		)
		(property "Value" ""
			(at 0 0 90)
			(layer "B.Fab")
			(effects
				(font
					(size 1.27 1.27)
				)
				(justify mirror)
			)
		)
		(duplicate_pad_numbers_are_jumpers no)
		(fp_line
			(start 0.299974 -0.150114)
			(end -0.299974 -0.150114)
			(stroke
				(width 0.1)
				(type default)
			)
			(layer "B.Fab")
		)
		(fp_line
			(start -0.299974 -0.150114)
			(end -0.299974 0.150114)
			(stroke
				(width 0.1)
				(type default)
			)
			(layer "B.Fab")
		)
		(fp_line
			(start 0.299974 0.150114)
			(end 0.299974 -0.150114)
			(stroke
				(width 0.1)
				(type default)
			)
			(layer "B.Fab")
		)
		(fp_line
			(start -0.299974 0.150114)
			(end 0.299974 0.150114)
			(stroke
				(width 0.1)
				(type default)
			)
			(layer "B.Fab")
		)
		(pad "1" smd rect
			(at 0.2667 0 270)
			(size 0.3048 0.381)
			(layers "B.Cu" "B.Mask" "B.Paste")
			(net "P0V8_SERDES_VDDA_PEX0")
		)
		(pad "2" smd rect
			(at -0.2667 0 270)
			(size 0.3048 0.381)
			(layers "B.Cu" "B.Mask" "B.Paste")
			(net "GND")
		)
	)
	(footprint ""
		(layer "B.Cu")
		(at 412.699962 -290.199826 90)
		(property "Reference" "C2003"
			(at 0 0 90)
			(layer "B.SilkS")
			(hide yes)
			(effects
				(font
					(size 1.27 1.27)
				)
				(justify mirror)
			)
		)
		(property "Value" ""
			(at 0 0 90)
			(layer "B.Fab")
			(effects
				(font
					(size 1.27 1.27)
				)
				(justify mirror)
			)
		)
		(duplicate_pad_numbers_are_jumpers no)
		(fp_line
			(start 0.299974 -0.150114)
			(end -0.299974 -0.150114)
			(stroke
				(width 0.1)
				(type default)
			)
			(layer "B.Fab")
		)
		(fp_line
			(start -0.299974 -0.150114)
			(end -0.299974 0.150114)
			(stroke
				(width 0.1)
				(type default)
			)
			(layer "B.Fab")
		)
		(fp_line
			(start 0.299974 0.150114)
			(end 0.299974 -0.150114)
			(stroke
				(width 0.1)
				(type default)
			)
			(layer "B.Fab")
		)
		(fp_line
			(start -0.299974 0.150114)
			(end 0.299974 0.150114)
			(stroke
				(width 0.1)
				(type default)
			)
			(layer "B.Fab")
		)
		(pad "1" smd rect
			(at 0.2667 0 270)
			(size 0.3048 0.381)
			(layers "B.Cu" "B.Mask" "B.Paste")
			(net "P0V8_SERDES_VDDA_PEX3")
		)
		(pad "2" smd rect
			(at -0.2667 0 270)
			(size 0.3048 0.381)
			(layers "B.Cu" "B.Mask" "B.Paste")
			(net "GND")
		)
	)
	(footprint ""
		(layer "B.Cu")
		(at 140.640816 -202.282806 180)
		(property "Reference" "C2599"
			(at 0 0 0)
			(layer "B.SilkS")
			(hide yes)
			(effects
				(font
					(size 1.27 1.27)
				)
				(justify mirror)
			)
		)
		(property "Value" ""
			(at 0 0 0)
			(layer "B.Fab")
			(effects
				(font
					(size 1.27 1.27)
				)
				(justify mirror)
			)
		)
		(duplicate_pad_numbers_are_jumpers no)
		(fp_line
			(start 0.7874 0.4064)
			(end 0.7874 -0.4064)
			(stroke
				(width 0.1524)
				(type default)
			)
			(layer "B.SilkS")
		)
		(fp_line
			(start 0.7874 -0.4064)
			(end -0.7874 -0.4064)
			(stroke
				(width 0.1524)
				(type default)
			)
			(layer "B.SilkS")
		)
		(fp_line
			(start -0.7874 0.4064)
			(end 0.7874 0.4064)
			(stroke
				(width 0.1524)
				(type default)
			)
			(layer "B.SilkS")
		)
		(fp_line
			(start -0.7874 -0.4064)
			(end -0.7874 0.4064)
			(stroke
				(width 0.1524)
				(type default)
			)
			(layer "B.SilkS")
		)
		(fp_line
			(start 0.67945 0.3048)
			(end 0.67945 -0.305054)
			(stroke
				(width 0.1)
				(type default)
			)
			(layer "B.Fab")
		)
		(fp_line
			(start 0.67945 -0.305054)
			(end 0.12065 -0.305054)
			(stroke
				(width 0.1)
				(type default)
			)
			(layer "B.Fab")
		)
		(fp_line
			(start 0.12065 0.3048)
			(end 0.67945 0.3048)
			(stroke
				(width 0.1)
				(type default)
			)
			(layer "B.Fab")
		)
		(fp_line
			(start 0.12065 0.2794)
			(end 0.12065 0.3048)
			(stroke
				(width 0.1)
				(type default)
			)
			(layer "B.Fab")
		)
		(fp_line
			(start 0.12065 -0.2794)
			(end -0.12065 -0.2794)
			(stroke
				(width 0.1)
				(type default)
			)
			(layer "B.Fab")
		)
		(fp_line
			(start 0.12065 -0.305054)
			(end 0.12065 -0.2794)
			(stroke
				(width 0.1)
				(type default)
			)
			(layer "B.Fab")
		)
		(fp_line
			(start -0.120396 0.3048)
			(end -0.120396 0.2794)
			(stroke
				(width 0.1)
				(type default)
			)
			(layer "B.Fab")
		)
		(fp_line
			(start -0.120396 0.2794)
			(end 0.12065 0.2794)
			(stroke
				(width 0.1)
				(type default)
			)
			(layer "B.Fab")
		)
		(fp_line
			(start -0.12065 -0.2794)
			(end -0.12065 -0.3048)
			(stroke
				(width 0.1)
				(type default)
			)
			(layer "B.Fab")
		)
		(fp_line
			(start -0.12065 -0.3048)
			(end -0.67945 -0.3048)
			(stroke
				(width 0.1)
				(type default)
			)
			(layer "B.Fab")
		)
		(fp_line
			(start -0.67945 0.3048)
			(end -0.120396 0.3048)
			(stroke
				(width 0.1)
				(type default)
			)
			(layer "B.Fab")
		)
		(fp_line
			(start -0.67945 -0.3048)
			(end -0.67945 0.3048)
			(stroke
				(width 0.1)
				(type default)
			)
			(layer "B.Fab")
		)
		(pad "1" smd circle
			(at 0.40005 0)
			(size 0 0)
			(layers "B.Cu" "B.Mask" "B.Paste")
			(net "P3V3_CLI_VPLL")
		)
		(pad "2" smd circle
			(at -0.40005 0)
			(size 0 0)
			(layers "B.Cu" "B.Mask" "B.Paste")
			(net "GND")
		)
	)
	(footprint ""
		(layer "B.Cu")
		(at 305.149758 -296.8498 180)
		(property "Reference" "C3296"
			(at 0 0 0)
			(layer "B.SilkS")
			(hide yes)
			(effects
				(font
					(size 1.27 1.27)
				)
				(justify mirror)
			)
		)
		(property "Value" ""
			(at 0 0 0)
			(layer "B.Fab")
			(effects
				(font
					(size 1.27 1.27)
				)
				(justify mirror)
			)
		)
		(duplicate_pad_numbers_are_jumpers no)
		(fp_line
			(start 0.299974 0.150114)
			(end 0.299974 -0.150114)
			(stroke
				(width 0.1)
				(type default)
			)
			(layer "B.Fab")
		)
		(fp_line
			(start 0.299974 -0.150114)
			(end -0.299974 -0.150114)
			(stroke
				(width 0.1)
				(type default)
			)
			(layer "B.Fab")
		)
		(fp_line
			(start -0.299974 0.150114)
			(end 0.299974 0.150114)
			(stroke
				(width 0.1)
				(type default)
			)
			(layer "B.Fab")
		)
		(fp_line
			(start -0.299974 -0.150114)
			(end -0.299974 0.150114)
			(stroke
				(width 0.1)
				(type default)
			)
			(layer "B.Fab")
		)
		(pad "1" smd rect
			(at 0.2667 0)
			(size 0.3048 0.381)
			(layers "B.Cu" "B.Mask" "B.Paste")
			(net "P1V25_SERDES_VDDPLL_PEX2")
		)
		(pad "2" smd rect
			(at -0.2667 0)
			(size 0.3048 0.381)
			(layers "B.Cu" "B.Mask" "B.Paste")
			(net "GND")
		)
	)
	(footprint ""
		(layer "B.Cu")
		(at 174.800006 -290.199826 90)
		(property "Reference" "C1433"
			(at 0 0 90)
			(layer "B.SilkS")
			(hide yes)
			(effects
				(font
					(size 1.27 1.27)
				)
				(justify mirror)
			)
		)
		(property "Value" ""
			(at 0 0 90)
			(layer "B.Fab")
			(effects
				(font
					(size 1.27 1.27)
				)
				(justify mirror)
			)
		)
		(duplicate_pad_numbers_are_jumpers no)
		(fp_line
			(start 0.299974 -0.150114)
			(end -0.299974 -0.150114)
			(stroke
				(width 0.1)
				(type default)
			)
			(layer "B.Fab")
		)
		(fp_line
			(start -0.299974 -0.150114)
			(end -0.299974 0.150114)
			(stroke
				(width 0.1)
				(type default)
			)
			(layer "B.Fab")
		)
		(fp_line
			(start 0.299974 0.150114)
			(end 0.299974 -0.150114)
			(stroke
				(width 0.1)
				(type default)
			)
			(layer "B.Fab")
		)
		(fp_line
			(start -0.299974 0.150114)
			(end 0.299974 0.150114)
			(stroke
				(width 0.1)
				(type default)
			)
			(layer "B.Fab")
		)
		(pad "1" smd rect
			(at 0.2667 0 270)
			(size 0.3048 0.381)
			(layers "B.Cu" "B.Mask" "B.Paste")
			(net "P0V8_SERDES_VDDA_PEX1")
		)
		(pad "2" smd rect
			(at -0.2667 0 270)
			(size 0.3048 0.381)
			(layers "B.Cu" "B.Mask" "B.Paste")
			(net "GND")
		)
	)
	(footprint ""
		(layer "B.Cu")
		(at 67.249802 -303.499774 -90)
		(property "Reference" "C2924"
			(at 0 0 90)
			(layer "B.SilkS")
			(hide yes)
			(effects
				(font
					(size 1.27 1.27)
				)
				(justify mirror)
			)
		)
		(property "Value" ""
			(at 0 0 90)
			(layer "B.Fab")
			(effects
				(font
					(size 1.27 1.27)
				)
				(justify mirror)
			)
		)
		(duplicate_pad_numbers_are_jumpers no)
		(fp_line
			(start -0.299974 0.150114)
			(end 0.299974 0.150114)
			(stroke
				(width 0.1)
				(type default)
			)
			(layer "B.Fab")
		)
		(fp_line
			(start 0.299974 0.150114)
			(end 0.299974 -0.150114)
			(stroke
				(width 0.1)
				(type default)
			)
			(layer "B.Fab")
		)
		(fp_line
			(start -0.299974 -0.150114)
			(end -0.299974 0.150114)
			(stroke
				(width 0.1)
				(type default)
			)
			(layer "B.Fab")
		)
		(fp_line
			(start 0.299974 -0.150114)
			(end -0.299974 -0.150114)
			(stroke
				(width 0.1)
				(type default)
			)
			(layer "B.Fab")
		)
		(pad "1" smd rect
			(at 0.2667 0 90)
			(size 0.3048 0.381)
			(layers "B.Cu" "B.Mask" "B.Paste")
			(net "P1V25_PEX0")
		)
		(pad "2" smd rect
			(at -0.2667 0 90)
			(size 0.3048 0.381)
			(layers "B.Cu" "B.Mask" "B.Paste")
			(net "GND")
		)
	)
	(footprint ""
		(layer "B.Cu")
		(at 398.87017 -305.399948 -90)
		(property "Reference" "C3493"
			(at 0 0 90)
			(layer "B.SilkS")
			(hide yes)
			(effects
				(font
					(size 1.27 1.27)
				)
				(justify mirror)
			)
		)
		(property "Value" ""
			(at 0 0 90)
			(layer "B.Fab")
			(effects
				(font
					(size 1.27 1.27)
				)
				(justify mirror)
			)
		)
		(duplicate_pad_numbers_are_jumpers no)
		(fp_line
			(start -0.299974 0.150114)
			(end 0.299974 0.150114)
			(stroke
				(width 0.1)
				(type default)
			)
			(layer "B.Fab")
		)
		(fp_line
			(start 0.299974 0.150114)
			(end 0.299974 -0.150114)
			(stroke
				(width 0.1)
				(type default)
			)
			(layer "B.Fab")
		)
		(fp_line
			(start -0.299974 -0.150114)
			(end -0.299974 0.150114)
			(stroke
				(width 0.1)
				(type default)
			)
			(layer "B.Fab")
		)
		(fp_line
			(start 0.299974 -0.150114)
			(end -0.299974 -0.150114)
			(stroke
				(width 0.1)
				(type default)
			)
			(layer "B.Fab")
		)
		(pad "1" smd rect
			(at 0.2667 0 90)
			(size 0.3048 0.381)
			(layers "B.Cu" "B.Mask" "B.Paste")
			(net "P1V25_SERDES_VDDPLL_PEX3")
		)
		(pad "2" smd rect
			(at -0.2667 0 90)
			(size 0.3048 0.381)
			(layers "B.Cu" "B.Mask" "B.Paste")
			(net "GND")
		)
	)
	(footprint ""
		(layer "B.Cu")
		(at 373.422672 -220.924374 90)
		(property "Reference" "R3505"
			(at 0 0 90)
			(layer "B.SilkS")
			(hide yes)
			(effects
				(font
					(size 1.27 1.27)
				)
				(justify mirror)
			)
		)
		(property "Value" ""
			(at 0 0 90)
			(layer "B.Fab")
			(effects
				(font
					(size 1.27 1.27)
				)
				(justify mirror)
			)
		)
		(duplicate_pad_numbers_are_jumpers no)
		(fp_line
			(start 0.7874 -0.4064)
			(end -0.7874 -0.4064)
			(stroke
				(width 0.1524)
				(type default)
			)
			(layer "B.SilkS")
		)
		(fp_line
			(start -0.7874 -0.4064)
			(end -0.7874 0.4064)
			(stroke
				(width 0.1524)
				(type default)
			)
			(layer "B.SilkS")
		)
		(fp_line
			(start 0.7874 0.4064)
			(end 0.7874 -0.4064)
			(stroke
				(width 0.1524)
				(type default)
			)
			(layer "B.SilkS")
		)
		(fp_line
			(start -0.7874 0.4064)
			(end 0.7874 0.4064)
			(stroke
				(width 0.1524)
				(type default)
			)
			(layer "B.SilkS")
		)
		(fp_line
			(start 0.67945 -0.305054)
			(end 0.12065 -0.305054)
			(stroke
				(width 0.1)
				(type default)
			)
			(layer "B.Fab")
		)
		(fp_line
			(start 0.12065 -0.305054)
			(end 0.12065 -0.2794)
			(stroke
				(width 0.1)
				(type default)
			)
			(layer "B.Fab")
		)
		(fp_line
			(start -0.12065 -0.3048)
			(end -0.67945 -0.3048)
			(stroke
				(width 0.1)
				(type default)
			)
			(layer "B.Fab")
		)
		(fp_line
			(start -0.67945 -0.3048)
			(end -0.67945 0.3048)
			(stroke
				(width 0.1)
				(type default)
			)
			(layer "B.Fab")
		)
		(fp_line
			(start 0.12065 -0.2794)
			(end -0.12065 -0.2794)
			(stroke
				(width 0.1)
				(type default)
			)
			(layer "B.Fab")
		)
		(fp_line
			(start -0.12065 -0.2794)
			(end -0.12065 -0.3048)
			(stroke
				(width 0.1)
				(type default)
			)
			(layer "B.Fab")
		)
		(fp_line
			(start 0.12065 0.2794)
			(end 0.12065 0.3048)
			(stroke
				(width 0.1)
				(type default)
			)
			(layer "B.Fab")
		)
		(fp_line
			(start -0.120396 0.2794)
			(end 0.12065 0.2794)
			(stroke
				(width 0.1)
				(type default)
			)
			(layer "B.Fab")
		)
		(fp_line
			(start 0.67945 0.3048)
			(end 0.67945 -0.305054)
			(stroke
				(width 0.1)
				(type default)
			)
			(layer "B.Fab")
		)
		(fp_line
			(start 0.12065 0.3048)
			(end 0.67945 0.3048)
			(stroke
				(width 0.1)
				(type default)
			)
			(layer "B.Fab")
		)
		(fp_line
			(start -0.120396 0.3048)
			(end -0.120396 0.2794)
			(stroke
				(width 0.1)
				(type default)
			)
			(layer "B.Fab")
		)
		(fp_line
			(start -0.67945 0.3048)
			(end -0.120396 0.3048)
			(stroke
				(width 0.1)
				(type default)
			)
			(layer "B.Fab")
		)
		(pad "1" smd circle
			(at 0.40005 0 270)
			(size 0 0)
			(layers "B.Cu" "B.Mask" "B.Paste")
			(net "P1V8_PEX")
		)
		(pad "2" smd circle
			(at -0.40005 0 270)
			(size 0 0)
			(layers "B.Cu" "B.Mask" "B.Paste")
			(net "SPI_PEX3_SDIO3_R1")
		)
	)
)
